(kicad_pcb
	(version 20260206)
	(generator "pcbnew")
	(generator_version "10.0")
	(general
		(thickness 1.6)
		(legacy_teardrops no)
	)
	(paper "A4")
	(title_block
		(title "03242023_DA0F0TMBIJ0_F0T_Motherboard_J_brd_V01_OCP.brd")
		(comment 1 "Grand Teton / footprint 1682 of 6105 (U1), pads 1820-1927 of 4677")
	)
	(layers
		(0 "F.Cu" signal "TOP")
		(4 "In1.Cu" signal "GND")
		(6 "In2.Cu" signal "IN1")
		(8 "In3.Cu" signal "GND1")
		(10 "In4.Cu" signal "IN2")
		(12 "In5.Cu" signal "GND2")
		(14 "In6.Cu" signal "IN3")
		(16 "In7.Cu" signal "GND3")
		(18 "In8.Cu" signal "VCC")
		(20 "In9.Cu" signal "VCC1")
		(22 "In10.Cu" signal "GND4")
		(24 "In11.Cu" signal "IN4")
		(26 "In12.Cu" signal "GND5")
		(28 "In13.Cu" signal "IN5")
		(30 "In14.Cu" signal "GND6")
		(32 "In15.Cu" signal "IN6")
		(34 "In16.Cu" signal "GND7")
		(2 "B.Cu" signal "BOTTOM")
		(9 "F.Adhes" user "F.Adhesive")
		(11 "B.Adhes" user "B.Adhesive")
		(13 "F.Paste" user "Package Geometry/Pastemask Top")
		(15 "B.Paste" user "Package Geometry/Pastemask Bottom")
		(5 "F.SilkS" user "Ref Des/Silkscreen Top")
		(7 "B.SilkS" user "Ref Des/Silkscreen Bottom")
		(1 "F.Mask" user "Board Geometry/Soldermask Top")
		(3 "B.Mask" user "Board Geometry/Soldermask Bottom")
		(17 "Dwgs.User" user "User.Drawings")
		(19 "Cmts.User" user "User.Comments")
		(21 "Eco1.User" user "User.Eco1")
		(23 "Eco2.User" user "User.Eco2")
		(25 "Edge.Cuts" user "Board Geometry/Outline")
		(27 "Margin" user)
		(31 "F.CrtYd" user "Package Geometry/Place Bound Top")
		(29 "B.CrtYd" user "Package Geometry/Place Bound Bottom")
		(35 "F.Fab" user "Ref Des/Assembly Top")
		(33 "B.Fab" user "Ref Des/Assembly Bottom")
	)
	(footprint ""
		(layer "F.Cu")
		(at 111.93018 -251.76988 90)
		(property "Reference" "U1"
			(at -74.913236 41.548812 0)
			(unlocked yes)
			(layer "F.SilkS")
			(effects
				(font
					(size 1.6002 1.1938)
					(thickness 0.1524)
				)
				(justify left)
			)
		)
		(property "Value" ""
			(at 0 0 90)
			(layer "F.Fab")
			(effects
				(font
					(size 1.27 1.27)
				)
			)
		)
		(duplicate_pad_numbers_are_jumpers no)
		(pad "CD24" smd circle
			(at -18.705576 2.529586 270)
			(size 0.4318 0.4318)
			(layers "F.Cu" "F.Mask" "F.Paste")
			(net "TP_H_SBLINK4_CPU1_PMDOWN")
		)
		(pad "CD26" smd circle
			(at -17.07769 2.529586 270)
			(size 0.4318 0.4318)
			(layers "F.Cu" "F.Mask" "F.Paste")
			(net "NC_CPU1_MDFI_DIE10_EW0")
		)
		(pad "CD28" smd circle
			(at -15.450058 2.529586 270)
			(size 0.4318 0.4318)
			(layers "F.Cu" "F.Mask" "F.Paste")
			(net "TP_TRC_CPU1_PTI<1>")
		)
		(pad "CD30" smd circle
			(at -13.822426 2.529586 270)
			(size 0.4318 0.4318)
			(layers "F.Cu" "F.Mask" "F.Paste")
			(net "NC_CPU1_MDFI_DIE10_EW1")
		)
		(pad "CD32" smd circle
			(at -12.19454 2.529586 270)
			(size 0.4318 0.4318)
			(layers "F.Cu" "F.Mask" "F.Paste")
			(net "PVCCIN_CPU1")
		)
		(pad "CD34" smd circle
			(at -10.566654 2.529586 270)
			(size 0.4318 0.4318)
			(layers "F.Cu" "F.Mask" "F.Paste")
			(net "PVCCIN_CPU1")
		)
		(pad "CD36" smd circle
			(at -8.939022 2.529586 270)
			(size 0.4318 0.4318)
			(layers "F.Cu" "F.Mask" "F.Paste")
			(net "PVCCIN_CPU1")
		)
		(pad "CD38" smd circle
			(at -7.311136 2.529586 270)
			(size 0.4318 0.4318)
			(layers "F.Cu" "F.Mask" "F.Paste")
			(net "PVCCIN_CPU1")
		)
		(pad "CD40" smd circle
			(at -5.68325 2.529586 270)
			(size 0.4318 0.4318)
			(layers "F.Cu" "F.Mask" "F.Paste")
			(net "PVCCIN_CPU1")
		)
		(pad "CD42" smd circle
			(at -4.055618 2.529586 270)
			(size 0.4318 0.4318)
			(layers "F.Cu" "F.Mask" "F.Paste")
			(net "PVCCIN_CPU1")
		)
		(pad "CD44" smd circle
			(at -2.427732 2.529586 270)
			(size 0.4318 0.4318)
			(layers "F.Cu" "F.Mask" "F.Paste")
			(net "PVCCIN_CPU1")
		)
		(pad "CD47" smd circle
			(at 1.613916 2.639314 270)
			(size 0.4318 0.4318)
			(layers "F.Cu" "F.Mask" "F.Paste")
			(net "PVCCIN_CPU1")
		)
		(pad "CD49" smd circle
			(at 3.241802 2.639314 270)
			(size 0.4318 0.4318)
			(layers "F.Cu" "F.Mask" "F.Paste")
			(net "PVCCIN_CPU1")
		)
		(pad "CD51" smd circle
			(at 4.869434 2.639314 270)
			(size 0.4318 0.4318)
			(layers "F.Cu" "F.Mask" "F.Paste")
			(net "PVCCIN_CPU1")
		)
		(pad "CD53" smd circle
			(at 6.49732 2.639314 270)
			(size 0.4318 0.4318)
			(layers "F.Cu" "F.Mask" "F.Paste")
			(net "PVCCIN_CPU1")
		)
		(pad "CD55" smd circle
			(at 8.124952 2.639314 270)
			(size 0.4318 0.4318)
			(layers "F.Cu" "F.Mask" "F.Paste")
			(net "PVCCIN_CPU1")
		)
		(pad "CD57" smd circle
			(at 9.752838 2.639314 270)
			(size 0.4318 0.4318)
			(layers "F.Cu" "F.Mask" "F.Paste")
			(net "PVCCIN_CPU1")
		)
		(pad "CD59" smd circle
			(at 11.380724 2.639314 270)
			(size 0.4318 0.4318)
			(layers "F.Cu" "F.Mask" "F.Paste")
			(net "PVCCIN_CPU1")
		)
		(pad "CD61" smd circle
			(at 13.008356 2.639314 270)
			(size 0.4318 0.4318)
			(layers "F.Cu" "F.Mask" "F.Paste")
			(net "GND")
		)
		(pad "CD63" smd circle
			(at 14.635988 2.639314 270)
			(size 0.4318 0.4318)
			(layers "F.Cu" "F.Mask" "F.Paste")
			(net "SMB_S3M_CPU1_SDA")
		)
		(pad "CD65" smd circle
			(at 16.263874 2.639314 270)
			(size 0.4318 0.4318)
			(layers "F.Cu" "F.Mask" "F.Paste")
			(net "TP_SGPIO_S3M_CPU1_GSXRST_N")
		)
		(pad "CD67" smd circle
			(at 17.89176 2.639314 270)
			(size 0.4318 0.4318)
			(layers "F.Cu" "F.Mask" "F.Paste")
			(net "PVPP_HBM_CPU1")
		)
		(pad "CD69" smd circle
			(at 19.519392 2.639314 270)
			(size 0.4318 0.4318)
			(layers "F.Cu" "F.Mask" "F.Paste")
			(net "TP_CPU1_SPARE11")
		)
		(pad "CD71" smd circle
			(at 21.147278 2.639314 270)
			(size 0.4318 0.4318)
			(layers "F.Cu" "F.Mask" "F.Paste")
			(net "CPU1_RSVD<82>")
		)
		(pad "CD73" smd circle
			(at 22.77491 2.639314 270)
			(size 0.4318 0.4318)
			(layers "F.Cu" "F.Mask" "F.Paste")
			(net "Net_709")
		)
		(pad "CD75" smd circle
			(at 24.402796 2.639314 270)
			(size 0.4318 0.4318)
			(layers "F.Cu" "F.Mask" "F.Paste")
			(net "GND")
		)
		(pad "CD77" smd circle
			(at 26.030682 2.639314 270)
			(size 0.4318 0.4318)
			(layers "F.Cu" "F.Mask" "F.Paste")
			(net "GND")
		)
		(pad "CD79" smd circle
			(at 27.658314 2.639314 270)
			(size 0.4318 0.4318)
			(layers "F.Cu" "F.Mask" "F.Paste")
			(net "PVCCIN_CPU1")
		)
		(pad "CD81" smd circle
			(at 29.2862 2.639314 270)
			(size 0.4318 0.4318)
			(layers "F.Cu" "F.Mask" "F.Paste")
			(net "PVCCIN_CPU1")
		)
		(pad "CD83" smd circle
			(at 30.914086 2.639314 270)
			(size 0.4318 0.4318)
			(layers "F.Cu" "F.Mask" "F.Paste")
			(net "PVCCIN_CPU1")
		)
		(pad "CD85" smd circle
			(at 32.541718 2.639314 270)
			(size 0.4318 0.4318)
			(layers "F.Cu" "F.Mask" "F.Paste")
			(net "PVCCIN_CPU1")
		)
		(pad "CD87" smd circle
			(at 34.169604 2.639314 270)
			(size 0.4318 0.4318)
			(layers "F.Cu" "F.Mask" "F.Paste")
			(net "PVCCIN_CPU1")
		)
		(pad "CD89" smd circle
			(at 35.797236 2.639314 270)
			(size 0.4318 0.4318)
			(layers "F.Cu" "F.Mask" "F.Paste")
			(net "PVCCIN_CPU1")
		)
		(pad "CE1" smd oval
			(at -37.425122 2.999486 180)
			(size 0.381 0.4826)
			(drill
				(offset 0 -0.0508)
			)
			(layers "F.Cu" "F.Mask" "F.Paste")
			(net "UPI_CPU0_CPU1_P0P1_DP<21>")
		)
		(pad "CE3" smd circle
			(at -35.797236 2.999486 270)
			(size 0.4318 0.4318)
			(layers "F.Cu" "F.Mask" "F.Paste")
			(net "GND")
		)
		(pad "CE5" smd circle
			(at -34.169604 2.999486 270)
			(size 0.4318 0.4318)
			(layers "F.Cu" "F.Mask" "F.Paste")
			(net "UPI_CPU1_CPU0_P1P0_DN<20>")
		)
		(pad "CE7" smd circle
			(at -32.541718 2.999486 270)
			(size 0.4318 0.4318)
			(layers "F.Cu" "F.Mask" "F.Paste")
			(net "PVCCD_HV_CPU1")
		)
		(pad "CE9" smd circle
			(at -30.914086 2.999486 270)
			(size 0.4318 0.4318)
			(layers "F.Cu" "F.Mask" "F.Paste")
			(net "P5E_CPU1_PE1_RX_DP<4>")
		)
		(pad "CE11" smd circle
			(at -29.2862 2.999486 270)
			(size 0.4318 0.4318)
			(layers "F.Cu" "F.Mask" "F.Paste")
			(net "VSENSE_PVCCINFAON_CPU1_DN")
		)
		(pad "CE13" smd circle
			(at -27.658314 2.999486 270)
			(size 0.4318 0.4318)
			(layers "F.Cu" "F.Mask" "F.Paste")
			(net "P5E_CPU1_PE1_TX_DN<5>")
		)
		(pad "CE15" smd circle
			(at -26.030682 2.999486 270)
			(size 0.4318 0.4318)
			(layers "F.Cu" "F.Mask" "F.Paste")
			(net "PVCCINFAON_CPU1")
		)
		(pad "CE17" smd circle
			(at -24.402796 2.999486 270)
			(size 0.4318 0.4318)
			(layers "F.Cu" "F.Mask" "F.Paste")
			(net "TP_DMI_CPU1_PCH_TX_DN<3>")
		)
		(pad "CE19" smd circle
			(at -22.77491 2.999486 270)
			(size 0.4318 0.4318)
			(layers "F.Cu" "F.Mask" "F.Paste")
			(net "PVCCINFAON_CPU1")
		)
		(pad "CE21" smd circle
			(at -21.147278 2.999486 270)
			(size 0.4318 0.4318)
			(layers "F.Cu" "F.Mask" "F.Paste")
			(net "NC_CPU1_PE1_APROBE<0>")
		)
		(pad "CE23" smd circle
			(at -19.519392 2.999486 270)
			(size 0.4318 0.4318)
			(layers "F.Cu" "F.Mask" "F.Paste")
			(net "TP_H_SBLINK6_CPU1_PMDOWN")
		)
		(pad "CE25" smd circle
			(at -17.89176 2.999486 270)
			(size 0.4318 0.4318)
			(layers "F.Cu" "F.Mask" "F.Paste")
			(net "TP_H_SBLINK4_CPU1_PMSYNC")
		)
		(pad "CE60" smd circle
			(at 12.19454 3.109468 270)
			(size 0.4318 0.4318)
			(layers "F.Cu" "F.Mask" "F.Paste")
			(net "GND")
		)
		(pad "CE62" smd circle
			(at 13.822426 3.109468 270)
			(size 0.4318 0.4318)
			(layers "F.Cu" "F.Mask" "F.Paste")
			(net "NC_CPU1_LGSSPARE3")
		)
		(pad "CE64" smd circle
			(at 15.450058 3.109468 270)
			(size 0.4318 0.4318)
			(layers "F.Cu" "F.Mask" "F.Paste")
			(net "SMB_S3M_CPU1_SCL")
		)
		(pad "CE66" smd circle
			(at 17.07769 3.109468 270)
			(size 0.4318 0.4318)
			(layers "F.Cu" "F.Mask" "F.Paste")
			(net "GND")
		)
		(pad "CE68" smd circle
			(at 18.705576 3.109468 270)
			(size 0.4318 0.4318)
			(layers "F.Cu" "F.Mask" "F.Paste")
			(net "PVPP_HBM_CPU1")
		)
		(pad "CE70" smd circle
			(at 20.333462 3.109468 270)
			(size 0.4318 0.4318)
			(layers "F.Cu" "F.Mask" "F.Paste")
			(net "CPU1_RSVD<85>")
		)
		(pad "CE72" smd circle
			(at 21.961094 3.109468 270)
			(size 0.4318 0.4318)
			(layers "F.Cu" "F.Mask" "F.Paste")
			(net "GND")
		)
		(pad "CE74" smd circle
			(at 23.58898 3.109468 270)
			(size 0.4318 0.4318)
			(layers "F.Cu" "F.Mask" "F.Paste")
			(net "PVCCFA_EHV_FIVRA_CPU1")
		)
		(pad "CE76" smd circle
			(at 25.216612 3.109468 270)
			(size 0.4318 0.4318)
			(layers "F.Cu" "F.Mask" "F.Paste")
			(net "GND")
		)
		(pad "CE78" smd circle
			(at 26.844498 3.109468 270)
			(size 0.4318 0.4318)
			(layers "F.Cu" "F.Mask" "F.Paste")
			(net "GND")
		)
		(pad "CE80" smd circle
			(at 28.472384 3.109468 270)
			(size 0.4318 0.4318)
			(layers "F.Cu" "F.Mask" "F.Paste")
			(net "PVCCIN_CPU1")
		)
		(pad "CE82" smd circle
			(at 30.100016 3.109468 270)
			(size 0.4318 0.4318)
			(layers "F.Cu" "F.Mask" "F.Paste")
			(net "PVCCIN_CPU1")
		)
		(pad "CE84" smd circle
			(at 31.727902 3.109468 270)
			(size 0.4318 0.4318)
			(layers "F.Cu" "F.Mask" "F.Paste")
			(net "PVCCIN_CPU1")
		)
		(pad "CE86" smd circle
			(at 33.355534 3.109468 270)
			(size 0.4318 0.4318)
			(layers "F.Cu" "F.Mask" "F.Paste")
			(net "PVCCIN_CPU1")
		)
		(pad "CE88" smd circle
			(at 34.98342 3.109468 270)
			(size 0.4318 0.4318)
			(layers "F.Cu" "F.Mask" "F.Paste")
			(net "PVCCIN_CPU1")
		)
		(pad "CE90" smd oval
			(at 36.611306 3.109468)
			(size 0.381 0.4826)
			(drill
				(offset 0 -0.0508)
			)
			(layers "F.Cu" "F.Mask" "F.Paste")
			(net "PVCCIN_CPU1")
		)
		(pad "CF2" smd circle
			(at -36.611306 3.469132 270)
			(size 0.4318 0.4318)
			(layers "F.Cu" "F.Mask" "F.Paste")
			(net "UPI_CPU0_CPU1_P0P1_DN<21>")
		)
		(pad "CF4" smd circle
			(at -34.98342 3.469132 270)
			(size 0.4318 0.4318)
			(layers "F.Cu" "F.Mask" "F.Paste")
			(net "GND")
		)
		(pad "CF6" smd circle
			(at -33.355534 3.469132 270)
			(size 0.4318 0.4318)
			(layers "F.Cu" "F.Mask" "F.Paste")
			(net "UPI_CPU1_CPU0_P1P0_DP<20>")
		)
		(pad "CF8" smd circle
			(at -31.727902 3.469132 270)
			(size 0.4318 0.4318)
			(layers "F.Cu" "F.Mask" "F.Paste")
			(net "GND")
		)
		(pad "CF10" smd circle
			(at -30.100016 3.469132 270)
			(size 0.4318 0.4318)
			(layers "F.Cu" "F.Mask" "F.Paste")
			(net "P5E_CPU1_PE1_RX_DN<4>")
		)
		(pad "CF12" smd circle
			(at -28.472384 3.469132 270)
			(size 0.4318 0.4318)
			(layers "F.Cu" "F.Mask" "F.Paste")
			(net "GND")
		)
		(pad "CF14" smd circle
			(at -26.844498 3.469132 270)
			(size 0.4318 0.4318)
			(layers "F.Cu" "F.Mask" "F.Paste")
			(net "P5E_CPU1_PE1_TX_DN<4>")
		)
		(pad "CF16" smd circle
			(at -25.216612 3.469132 270)
			(size 0.4318 0.4318)
			(layers "F.Cu" "F.Mask" "F.Paste")
			(net "GND")
		)
		(pad "CF18" smd circle
			(at -23.58898 3.469132 270)
			(size 0.4318 0.4318)
			(layers "F.Cu" "F.Mask" "F.Paste")
			(net "TP_DMI_CPU1_PCH_TX_DN<4>")
		)
		(pad "CF20" smd circle
			(at -21.961094 3.469132 270)
			(size 0.4318 0.4318)
			(layers "F.Cu" "F.Mask" "F.Paste")
			(net "GND")
		)
		(pad "CF22" smd circle
			(at -20.333462 3.469132 270)
			(size 0.4318 0.4318)
			(layers "F.Cu" "F.Mask" "F.Paste")
			(net "NC_CPU1_MDFI_DIE10_NS0")
		)
		(pad "CF24" smd circle
			(at -18.705576 3.469132 270)
			(size 0.4318 0.4318)
			(layers "F.Cu" "F.Mask" "F.Paste")
			(net "TP_H_SBLINK7_CPU1_PMSYNC")
		)
		(pad "CF26" smd circle
			(at -17.07769 3.469132 270)
			(size 0.4318 0.4318)
			(layers "F.Cu" "F.Mask" "F.Paste")
			(net "H_CPU1_MEMHOT_OUT_LVC1_R_N")
		)
		(pad "CF61" smd circle
			(at 13.008356 3.579114 270)
			(size 0.4318 0.4318)
			(layers "F.Cu" "F.Mask" "F.Paste")
			(net "PUD_PCH_BOOT_MODE_CPU1")
		)
		(pad "CF63" smd circle
			(at 14.635988 3.579114 270)
			(size 0.4318 0.4318)
			(layers "F.Cu" "F.Mask" "F.Paste")
			(net "TP_SGPIO_S3M_CPU1_GSXCLK")
		)
		(pad "CF65" smd circle
			(at 16.263874 3.579114 270)
			(size 0.4318 0.4318)
			(layers "F.Cu" "F.Mask" "F.Paste")
			(net "TP_SGPIO_S3M_CPU1_GSXDOUT")
		)
		(pad "CF67" smd circle
			(at 17.89176 3.579114 270)
			(size 0.4318 0.4318)
			(layers "F.Cu" "F.Mask" "F.Paste")
			(net "PVPP_HBM_CPU1")
		)
		(pad "CF69" smd circle
			(at 19.519392 3.579114 270)
			(size 0.4318 0.4318)
			(layers "F.Cu" "F.Mask" "F.Paste")
			(net "GND")
		)
		(pad "CF71" smd circle
			(at 21.147278 3.579114 270)
			(size 0.4318 0.4318)
			(layers "F.Cu" "F.Mask" "F.Paste")
			(net "GND")
		)
		(pad "CF73" smd circle
			(at 22.77491 3.579114 270)
			(size 0.4318 0.4318)
			(layers "F.Cu" "F.Mask" "F.Paste")
			(net "Net_733")
		)
		(pad "CF75" smd circle
			(at 24.402796 3.579114 270)
			(size 0.4318 0.4318)
			(layers "F.Cu" "F.Mask" "F.Paste")
			(net "Net_736")
		)
		(pad "CF77" smd circle
			(at 26.030682 3.579114 270)
			(size 0.4318 0.4318)
			(layers "F.Cu" "F.Mask" "F.Paste")
			(net "Net_714")
		)
		(pad "CF79" smd circle
			(at 27.658314 3.579114 270)
			(size 0.4318 0.4318)
			(layers "F.Cu" "F.Mask" "F.Paste")
			(net "PVCCIN_CPU1")
		)
		(pad "CF81" smd circle
			(at 29.2862 3.579114 270)
			(size 0.4318 0.4318)
			(layers "F.Cu" "F.Mask" "F.Paste")
			(net "PVCCIN_CPU1")
		)
		(pad "CF83" smd circle
			(at 30.914086 3.579114 270)
			(size 0.4318 0.4318)
			(layers "F.Cu" "F.Mask" "F.Paste")
			(net "PVCCIN_CPU1")
		)
		(pad "CF85" smd circle
			(at 32.541718 3.579114 270)
			(size 0.4318 0.4318)
			(layers "F.Cu" "F.Mask" "F.Paste")
			(net "PVCCIN_CPU1")
		)
		(pad "CF87" smd circle
			(at 34.169604 3.579114 270)
			(size 0.4318 0.4318)
			(layers "F.Cu" "F.Mask" "F.Paste")
			(net "PVCCIN_CPU1")
		)
		(pad "CF89" smd circle
			(at 35.797236 3.579114 270)
			(size 0.4318 0.4318)
			(layers "F.Cu" "F.Mask" "F.Paste")
			(net "PVCCIN_CPU1")
		)
		(pad "CF91" smd oval
			(at 37.425122 3.579114)
			(size 0.381 0.4826)
			(drill
				(offset 0 -0.0508)
			)
			(layers "F.Cu" "F.Mask" "F.Paste")
			(net "PVCCIN_CPU1")
		)
		(pad "CG1" smd oval
			(at -37.425122 3.939286 180)
			(size 0.381 0.4826)
			(drill
				(offset 0 -0.0508)
			)
			(layers "F.Cu" "F.Mask" "F.Paste")
			(net "GND")
		)
		(pad "CG3" smd circle
			(at -35.797236 3.939286 270)
			(size 0.4318 0.4318)
			(layers "F.Cu" "F.Mask" "F.Paste")
			(net "UPI_CPU0_CPU1_P0P1_DP<20>")
		)
		(pad "CG5" smd circle
			(at -34.169604 3.939286 270)
			(size 0.4318 0.4318)
			(layers "F.Cu" "F.Mask" "F.Paste")
			(net "GND")
		)
		(pad "CG7" smd circle
			(at -32.541718 3.939286 270)
			(size 0.4318 0.4318)
			(layers "F.Cu" "F.Mask" "F.Paste")
			(net "UPI_CPU1_CPU0_P1P0_DP<19>")
		)
		(pad "CG9" smd circle
			(at -30.914086 3.939286 270)
			(size 0.4318 0.4318)
			(layers "F.Cu" "F.Mask" "F.Paste")
			(net "GND")
		)
		(pad "CG11" smd circle
			(at -29.2862 3.939286 270)
			(size 0.4318 0.4318)
			(layers "F.Cu" "F.Mask" "F.Paste")
			(net "P5E_CPU1_PE1_RX_DN<3>")
		)
		(pad "CG13" smd circle
			(at -27.658314 3.939286 270)
			(size 0.4318 0.4318)
			(layers "F.Cu" "F.Mask" "F.Paste")
			(net "GND")
		)
		(pad "CG15" smd circle
			(at -26.030682 3.939286 270)
			(size 0.4318 0.4318)
			(layers "F.Cu" "F.Mask" "F.Paste")
			(net "P5E_CPU1_PE1_TX_DP<4>")
		)
		(pad "CG17" smd circle
			(at -24.402796 3.939286 270)
			(size 0.4318 0.4318)
			(layers "F.Cu" "F.Mask" "F.Paste")
			(net "GND")
		)
		(pad "CG19" smd circle
			(at -22.77491 3.939286 270)
			(size 0.4318 0.4318)
			(layers "F.Cu" "F.Mask" "F.Paste")
			(net "TP_DMI_CPU1_PCH_TX_DP<4>")
		)
		(pad "CG21" smd circle
			(at -21.147278 3.939286 270)
			(size 0.4318 0.4318)
			(layers "F.Cu" "F.Mask" "F.Paste")
			(net "GND")
		)
		(pad "CG23" smd circle
			(at -19.519392 3.939286 270)
			(size 0.4318 0.4318)
			(layers "F.Cu" "F.Mask" "F.Paste")
			(net "GND")
		)
		(pad "CG25" smd circle
			(at -17.89176 3.939286 270)
			(size 0.4318 0.4318)
			(layers "F.Cu" "F.Mask" "F.Paste")
			(net "GND")
		)
		(pad "CG60" smd circle
			(at 12.19454 4.049268 270)
			(size 0.4318 0.4318)
			(layers "F.Cu" "F.Mask" "F.Paste")
			(net "TP_CPU1_SPARE10")
		)
		(pad "CG62" smd circle
			(at 13.822426 4.049268 270)
			(size 0.4318 0.4318)
			(layers "F.Cu" "F.Mask" "F.Paste")
			(net "GND")
		)
		(pad "CG64" smd circle
			(at 15.450058 4.049268 270)
			(size 0.4318 0.4318)
			(layers "F.Cu" "F.Mask" "F.Paste")
			(net "GND")
		)
		(pad "CG66" smd circle
			(at 17.07769 4.049268 270)
			(size 0.4318 0.4318)
			(layers "F.Cu" "F.Mask" "F.Paste")
			(net "FM_CPU1_SKTOCC_LVT3_N")
		)
	)
)
